(kicad_pcb
	(version 20260206)
	(generator "pcbnew")
	(generator_version "10.0")
	(general
		(thickness 1.6)
		(legacy_teardrops no)
	)
	(paper "A4")
	(title_block
		(title "Wiwynn_Tioga_Pass_MB.brd")
		(comment 1 "Tioga Pass / footprints 4762-4768 of 4770")
	)
	(layers
		(0 "F.Cu" signal "TOP")
		(4 "In1.Cu" signal "L2GND")
		(6 "In2.Cu" signal "L3")
		(8 "In3.Cu" signal "L4GND")
		(10 "In4.Cu" signal "L5")
		(12 "In5.Cu" signal "L6GND")
		(14 "In6.Cu" signal "L7VCC")
		(16 "In7.Cu" signal "L8VCC")
		(18 "In8.Cu" signal "L9GND")
		(20 "In9.Cu" signal "L10")
		(22 "In10.Cu" signal "L11GND")
		(24 "In11.Cu" signal "L12")
		(26 "In12.Cu" signal "L13GND")
		(2 "B.Cu" signal "BOTTOM")
		(9 "F.Adhes" user "F.Adhesive")
		(11 "B.Adhes" user "B.Adhesive")
		(13 "F.Paste" user "Package Geometry/Pastemask Top")
		(15 "B.Paste" user "Package Geometry/Pastemask Bottom")
		(5 "F.SilkS" user "Ref Des/Silkscreen Top")
		(7 "B.SilkS" user "Ref Des/Silkscreen Bottom")
		(1 "F.Mask" user "Board Geometry/Soldermask Top")
		(3 "B.Mask" user "Board Geometry/Soldermask Bottom")
		(17 "Dwgs.User" user "User.Drawings")
		(19 "Cmts.User" user "User.Comments")
		(21 "Eco1.User" user "User.Eco1")
		(23 "Eco2.User" user "User.Eco2")
		(25 "Edge.Cuts" user "Board Geometry/Outline")
		(27 "Margin" user)
		(31 "F.CrtYd" user "Package Geometry/Place Bound Top")
		(29 "B.CrtYd" user "Package Geometry/Place Bound Bottom")
		(35 "F.Fab" user "Ref Des/Assembly Top")
		(33 "B.Fab" user "Ref Des/Assembly Bottom")
	)
	(footprint ""
		(layer "B.Cu")
		(at 405.9174 -33.4264 -90)
		(property "Reference" "R25W146"
			(at 0.8382 -0.67818 270)
			(unlocked yes)
			(layer "B.SilkS")
			(effects
				(font
					(size 0.4064 0.254)
					(thickness 0.1524)
				)
				(justify left mirror)
			)
		)
		(property "Value" ""
			(at 0 0 90)
			(layer "B.Fab")
			(effects
				(font
					(size 1.27 1.27)
				)
				(justify mirror)
			)
		)
		(duplicate_pad_numbers_are_jumpers no)
		(fp_poly
			(pts
				(xy 0.2794 -0.1016) (xy -0.2794 -0.1016) (xy -0.2794 0.9906) (xy 0.2794 0.9906)
			)
			(stroke
				(width 0)
				(type default)
			)
			(fill no)
			(layer "B.CrtYd")
		)
		(fp_line
			(start -0.2794 0.9906)
			(end -0.2794 -0.1016)
			(stroke
				(width 0.1)
				(type default)
			)
			(layer "B.Fab")
		)
		(fp_line
			(start 0.2794 0.9906)
			(end -0.2794 0.9906)
			(stroke
				(width 0.1)
				(type default)
			)
			(layer "B.Fab")
		)
		(fp_line
			(start -0.2794 -0.1016)
			(end 0.2794 -0.1016)
			(stroke
				(width 0.1)
				(type default)
			)
			(layer "B.Fab")
		)
		(fp_line
			(start 0.2794 -0.1016)
			(end 0.2794 0.9906)
			(stroke
				(width 0.1)
				(type default)
			)
			(layer "B.Fab")
		)
		(pad "1" smd rect
			(at 0 0 90)
			(size 0.508 0.508)
			(layers "B.Cu" "B.Mask" "B.Paste")
			(net "GND")
		)
		(pad "2" smd rect
			(at 0 0.889 90)
			(size 0.508 0.508)
			(layers "B.Cu" "B.Mask" "B.Paste")
			(net "RMII_BMC_OCP_TXEN")
		)
		(zone
			(layer "B.Cu")
			(hatch none 0.5)
			(connect_pads
				(clearance 0)
			)
			(min_thickness 0.25)
			(keepout
				(tracks not_allowed)
				(vias allowed)
				(pads allowed)
				(copperpour not_allowed)
				(footprints allowed)
			)
			(placement
				(enabled no)
				(sheetname "")
			)
			(fill
				(thermal_gap 0.5)
				(thermal_bridge_width 0.5)
				(island_removal_mode 0)
			)
			(polygon
				(pts
					(xy 405.2824 -33.1724) (xy 405.2824 -33.6804) (xy 405.6634 -33.6804) (xy 405.6634 -33.1724)
				)
			)
		)
		(zone
			(layer "B.Cu")
			(hatch none 0.5)
			(connect_pads
				(clearance 0)
			)
			(min_thickness 0.25)
			(keepout
				(tracks allowed)
				(vias not_allowed)
				(pads allowed)
				(copperpour not_allowed)
				(footprints allowed)
			)
			(placement
				(enabled no)
				(sheetname "")
			)
			(fill
				(thermal_gap 0.5)
				(thermal_bridge_width 0.5)
				(island_removal_mode 0)
			)
			(polygon
				(pts
					(xy 405.6634 -33.1724) (xy 405.6634 -33.6804) (xy 405.2824 -33.6804) (xy 405.2824 -33.1724)
				)
			)
		)
	)
	(footprint ""
		(layer "B.Cu")
		(at 407.654506 -32.661352 180)
		(property "Reference" "R25W85"
			(at 0.8382 -0.67818 180)
			(unlocked yes)
			(layer "B.SilkS")
			(effects
				(font
					(size 0.4064 0.254)
					(thickness 0.1524)
				)
				(justify left mirror)
			)
		)
		(property "Value" ""
			(at 0 0 0)
			(layer "B.Fab")
			(effects
				(font
					(size 1.27 1.27)
				)
				(justify mirror)
			)
		)
		(duplicate_pad_numbers_are_jumpers no)
		(fp_poly
			(pts
				(xy 0.2794 -0.1016) (xy -0.2794 -0.1016) (xy -0.2794 0.9906) (xy 0.2794 0.9906)
			)
			(stroke
				(width 0)
				(type default)
			)
			(fill no)
			(layer "B.CrtYd")
		)
		(fp_line
			(start 0.2794 0.9906)
			(end -0.2794 0.9906)
			(stroke
				(width 0.1)
				(type default)
			)
			(layer "B.Fab")
		)
		(fp_line
			(start 0.2794 -0.1016)
			(end 0.2794 0.9906)
			(stroke
				(width 0.1)
				(type default)
			)
			(layer "B.Fab")
		)
		(fp_line
			(start -0.2794 0.9906)
			(end -0.2794 -0.1016)
			(stroke
				(width 0.1)
				(type default)
			)
			(layer "B.Fab")
		)
		(fp_line
			(start -0.2794 -0.1016)
			(end 0.2794 -0.1016)
			(stroke
				(width 0.1)
				(type default)
			)
			(layer "B.Fab")
		)
		(pad "1" smd rect
			(at 0 0)
			(size 0.508 0.508)
			(layers "B.Cu" "B.Mask" "B.Paste")
			(net "RMII_BMC_OCP_TXEN_R")
		)
		(pad "2" smd rect
			(at 0 0.889)
			(size 0.508 0.508)
			(layers "B.Cu" "B.Mask" "B.Paste")
			(net "RMII_BMC_OCP_TXEN")
		)
		(zone
			(layer "B.Cu")
			(hatch none 0.5)
			(connect_pads
				(clearance 0)
			)
			(min_thickness 0.25)
			(keepout
				(tracks not_allowed)
				(vias allowed)
				(pads allowed)
				(copperpour not_allowed)
				(footprints allowed)
			)
			(placement
				(enabled no)
				(sheetname "")
			)
			(fill
				(thermal_gap 0.5)
				(thermal_bridge_width 0.5)
				(island_removal_mode 0)
			)
			(polygon
				(pts
					(xy 407.400506 -33.296352) (xy 407.908506 -33.296352) (xy 407.908506 -32.915352) (xy 407.400506 -32.915352)
				)
			)
		)
		(zone
			(layer "B.Cu")
			(hatch none 0.5)
			(connect_pads
				(clearance 0)
			)
			(min_thickness 0.25)
			(keepout
				(tracks allowed)
				(vias not_allowed)
				(pads allowed)
				(copperpour not_allowed)
				(footprints allowed)
			)
			(placement
				(enabled no)
				(sheetname "")
			)
			(fill
				(thermal_gap 0.5)
				(thermal_bridge_width 0.5)
				(island_removal_mode 0)
			)
			(polygon
				(pts
					(xy 407.400506 -32.915352) (xy 407.908506 -32.915352) (xy 407.908506 -33.296352) (xy 407.400506 -33.296352)
				)
			)
		)
	)
	(footprint ""
		(layer "B.Cu")
		(at 444.649606 -52.342034)
		(property "Reference" "C2R7"
			(at 0 0 0)
			(layer "B.SilkS")
			(hide yes)
			(effects
				(font
					(size 1.27 1.27)
				)
				(justify mirror)
			)
		)
		(property "Value" ""
			(at 0 0 0)
			(layer "B.Fab")
			(effects
				(font
					(size 1.27 1.27)
				)
				(justify mirror)
			)
		)
		(duplicate_pad_numbers_are_jumpers no)
		(fp_poly
			(pts
				(xy -0.3048 -0.1016) (xy -0.3048 0.9906) (xy 0.3048 0.9906) (xy 0.3048 -0.1016)
			)
			(stroke
				(width 0)
				(type default)
			)
			(fill no)
			(layer "B.CrtYd")
		)
		(fp_line
			(start -0.3048 -0.1016)
			(end 0.3048 -0.1016)
			(stroke
				(width 0.1)
				(type default)
			)
			(layer "B.Fab")
		)
		(fp_line
			(start -0.3048 0.9906)
			(end -0.3048 -0.1016)
			(stroke
				(width 0.1)
				(type default)
			)
			(layer "B.Fab")
		)
		(fp_line
			(start 0.3048 -0.1016)
			(end 0.3048 0.9906)
			(stroke
				(width 0.1)
				(type default)
			)
			(layer "B.Fab")
		)
		(fp_line
			(start 0.3048 0.9906)
			(end -0.3048 0.9906)
			(stroke
				(width 0.1)
				(type default)
			)
			(layer "B.Fab")
		)
		(pad "1" smd rect
			(at 0 0 180)
			(size 0.508 0.508)
			(layers "B.Cu" "B.Mask" "B.Paste")
			(net "P3E_CPU0_PE3_OCP_TXN<6>")
		)
		(pad "2" smd rect
			(at 0 0.889 180)
			(size 0.508 0.508)
			(layers "B.Cu" "B.Mask" "B.Paste")
			(net "P3E_OCP_CPU0_PE3_C_TXN<6>")
		)
		(zone
			(layer "B.Cu")
			(hatch none 0.5)
			(connect_pads
				(clearance 0)
			)
			(min_thickness 0.25)
			(keepout
				(tracks allowed)
				(vias not_allowed)
				(pads allowed)
				(copperpour not_allowed)
				(footprints allowed)
			)
			(placement
				(enabled no)
				(sheetname "")
			)
			(fill
				(thermal_gap 0.5)
				(thermal_bridge_width 0.5)
				(island_removal_mode 0)
			)
			(polygon
				(pts
					(xy 444.903606 -52.088034) (xy 444.395606 -52.088034) (xy 444.395606 -51.707034) (xy 444.903606 -51.707034)
				)
			)
		)
		(zone
			(layer "B.Cu")
			(hatch none 0.5)
			(connect_pads
				(clearance 0)
			)
			(min_thickness 0.25)
			(keepout
				(tracks not_allowed)
				(vias allowed)
				(pads allowed)
				(copperpour not_allowed)
				(footprints allowed)
			)
			(placement
				(enabled no)
				(sheetname "")
			)
			(fill
				(thermal_gap 0.5)
				(thermal_bridge_width 0.5)
				(island_removal_mode 0)
			)
			(polygon
				(pts
					(xy 444.903606 -51.707034) (xy 444.395606 -51.707034) (xy 444.395606 -52.088034) (xy 444.903606 -52.088034)
				)
			)
		)
	)
	(footprint ""
		(layer "B.Cu")
		(at 346.72524 -10.28446 -90)
		(property "Reference" "C7G35"
			(at 0 0 90)
			(layer "B.SilkS")
			(hide yes)
			(effects
				(font
					(size 1.27 1.27)
				)
				(justify mirror)
			)
		)
		(property "Value" "*"
			(at -1.1811 -2.8194 270)
			(unlocked yes)
			(layer "B.Fab")
			(hide yes)
			(effects
				(font
					(size 1.27 1.016)
					(thickness 0.1524)
				)
				(justify mirror)
			)
		)
		(property "Device Type" "SC1U10V2KX-4-GP_SMD-BCG6-SC1U1A"
			(at -1.1811 -4.3434 270)
			(unlocked yes)
			(layer "B.Fab")
			(hide yes)
			(effects
				(font
					(size 1.27 1.016)
					(thickness 0.1524)
				)
				(justify mirror)
			)
		)
		(duplicate_pad_numbers_are_jumpers no)
		(fp_rect
			(start 0.4318 0.9525)
			(end -0.4318 -0.9525)
			(stroke
				(width 0)
				(type default)
			)
			(fill no)
			(layer "B.CrtYd")
		)
		(fp_rect
			(start 0.4318 0.9525)
			(end -0.4318 -0.9525)
			(stroke
				(width 0)
				(type default)
			)
			(fill no)
			(layer "B.Fab")
		)
		(pad "1" smd custom
			(at 0 -0.4445 90)
			(size 0.1524 0.1524)
			(layers "B.Cu" "B.Mask" "B.Paste")
			(net "P5V_STBY")
			(options
				(clearance outline)
				(anchor circle)
			)
			(primitives
				(gr_poly
					(pts
						(arc
							(start 0.3048 0.2032)
							(mid 0.275042 0.275042)
							(end 0.2032 0.3048)
						)
						(arc
							(start -0.2032 0.3048)
							(mid -0.275042 0.275042)
							(end -0.3048 0.2032)
						)
						(arc
							(start -0.3048 -0.2032)
							(mid -0.275042 -0.275042)
							(end -0.2032 -0.3048)
						)
						(arc
							(start 0.2032 -0.3048)
							(mid 0.275042 -0.275042)
							(end 0.3048 -0.2032)
						)
					)
					(width 0)
					(fill yes)
				)
			)
		)
		(pad "2" smd custom
			(at 0 0.4445 90)
			(size 0.1524 0.1524)
			(layers "B.Cu" "B.Mask" "B.Paste")
			(net "GND")
			(options
				(clearance outline)
				(anchor circle)
			)
			(primitives
				(gr_poly
					(pts
						(arc
							(start 0.3048 0.2032)
							(mid 0.275042 0.275042)
							(end 0.2032 0.3048)
						)
						(arc
							(start -0.2032 0.3048)
							(mid -0.275042 0.275042)
							(end -0.3048 0.2032)
						)
						(arc
							(start -0.3048 -0.2032)
							(mid -0.275042 -0.275042)
							(end -0.2032 -0.3048)
						)
						(arc
							(start 0.2032 -0.3048)
							(mid 0.275042 -0.275042)
							(end 0.3048 -0.2032)
						)
					)
					(width 0)
					(fill yes)
				)
			)
		)
	)
	(footprint ""
		(layer "B.Cu")
		(at 470.8906 -131.2164 180)
		(property "Reference" "CR6W1"
			(at -1.06934 -0.39116 270)
			(unlocked yes)
			(layer "B.SilkS")
			(effects
				(font
					(size 0.4064 0.254)
					(thickness 0.1524)
				)
				(justify left mirror)
			)
		)
		(property "Value" ""
			(at 0 0 0)
			(layer "B.Fab")
			(effects
				(font
					(size 1.27 1.27)
				)
				(justify mirror)
			)
		)
		(duplicate_pad_numbers_are_jumpers no)
		(fp_line
			(start 1.18237 1.568958)
			(end 0.701548 0.736092)
			(stroke
				(width 0.1524)
				(type default)
			)
			(layer "B.SilkS")
		)
		(fp_line
			(start 0.701548 2.480564)
			(end 0.701548 1.568958)
			(stroke
				(width 0.1524)
				(type default)
			)
			(layer "B.SilkS")
		)
		(fp_line
			(start 0.701548 1.568958)
			(end 1.18237 1.568958)
			(stroke
				(width 0.1524)
				(type default)
			)
			(layer "B.SilkS")
		)
		(fp_line
			(start 0.701548 0.736092)
			(end 0.220726 1.568958)
			(stroke
				(width 0.1524)
				(type default)
			)
			(layer "B.SilkS")
		)
		(fp_line
			(start 0.701548 -0.38735)
			(end 0.701548 0.736092)
			(stroke
				(width 0.1524)
				(type default)
			)
			(layer "B.SilkS")
		)
		(fp_line
			(start 0.220726 1.568958)
			(end 0.701548 1.568958)
			(stroke
				(width 0.1524)
				(type default)
			)
			(layer "B.SilkS")
		)
		(fp_line
			(start 0.220726 0.736092)
			(end 1.18237 0.736092)
			(stroke
				(width 0.1524)
				(type default)
			)
			(layer "B.SilkS")
		)
		(fp_poly
			(pts
				(xy 0.67437 0.24384) (xy 0.67437 2.04216) (xy -0.67437 2.04216) (xy -0.67437 0.24384)
			)
			(stroke
				(width 0)
				(type default)
			)
			(fill no)
			(layer "B.CrtYd")
		)
		(fp_line
			(start 1.17602 1.554734)
			(end 0.695198 0.721868)
			(stroke
				(width 0.1)
				(type default)
			)
			(layer "B.Fab")
		)
		(fp_line
			(start 0.695198 1.554734)
			(end 0.695198 2.46634)
			(stroke
				(width 0.1)
				(type default)
			)
			(layer "B.Fab")
		)
		(fp_line
			(start 0.695198 0.721868)
			(end 0.695198 -0.401574)
			(stroke
				(width 0.1)
				(type default)
			)
			(layer "B.Fab")
		)
		(fp_line
			(start 0.695198 0.721868)
			(end 0.214376 1.554734)
			(stroke
				(width 0.1)
				(type default)
			)
			(layer "B.Fab")
		)
		(fp_line
			(start 0.67437 2.04216)
			(end -0.67437 2.04216)
			(stroke
				(width 0.1)
				(type default)
			)
			(layer "B.Fab")
		)
		(fp_line
			(start 0.67437 0.24384)
			(end 0.67437 2.04216)
			(stroke
				(width 0.1)
				(type default)
			)
			(layer "B.Fab")
		)
		(fp_line
			(start 0.214376 1.554734)
			(end 1.17602 1.554734)
			(stroke
				(width 0.1)
				(type default)
			)
			(layer "B.Fab")
		)
		(fp_line
			(start 0.214376 0.721868)
			(end 1.17602 0.721868)
			(stroke
				(width 0.1)
				(type default)
			)
			(layer "B.Fab")
		)
		(fp_line
			(start -0.67437 2.04216)
			(end -0.67437 0.24384)
			(stroke
				(width 0.1)
				(type default)
			)
			(layer "B.Fab")
		)
		(fp_line
			(start -0.67437 0.24384)
			(end 0.67437 0.24384)
			(stroke
				(width 0.1)
				(type default)
			)
			(layer "B.Fab")
		)
		(pad "1" smd rect
			(at 0 0)
			(size 0.4064 1.016)
			(layers "B.Cu" "B.Mask" "B.Paste")
			(net "FM_CPU_CATERR_LVT3_N")
		)
		(pad "2" smd rect
			(at 0 2.286)
			(size 0.4064 1.016)
			(layers "B.Cu" "B.Mask" "B.Paste")
			(net "FM_CPU_CATERR_MSMI_LVT3_N")
		)
	)
	(footprint ""
		(layer "B.Cu")
		(at 278.703024 -71.714614 180)
		(property "Reference" "C4P9"
			(at 0 0 0)
			(layer "B.SilkS")
			(hide yes)
			(effects
				(font
					(size 1.27 1.27)
				)
				(justify mirror)
			)
		)
		(property "Value" ""
			(at 0 0 0)
			(layer "B.Fab")
			(effects
				(font
					(size 1.27 1.27)
				)
				(justify mirror)
			)
		)
		(duplicate_pad_numbers_are_jumpers no)
		(fp_poly
			(pts
				(xy 0.7239 -0.2159) (xy -0.7239 -0.2159) (xy -0.7239 1.9939) (xy 0.7239 1.9939)
			)
			(stroke
				(width 0)
				(type default)
			)
			(fill no)
			(layer "B.CrtYd")
		)
		(fp_line
			(start 0.7239 1.9939)
			(end -0.7239 1.9939)
			(stroke
				(width 0.1)
				(type default)
			)
			(layer "B.Fab")
		)
		(fp_line
			(start 0.7239 -0.2159)
			(end 0.7239 1.9939)
			(stroke
				(width 0.1)
				(type default)
			)
			(layer "B.Fab")
		)
		(fp_line
			(start -0.7239 1.9939)
			(end -0.7239 -0.2159)
			(stroke
				(width 0.1)
				(type default)
			)
			(layer "B.Fab")
		)
		(fp_line
			(start -0.7239 -0.2159)
			(end 0.7239 -0.2159)
			(stroke
				(width 0.1)
				(type default)
			)
			(layer "B.Fab")
		)
		(pad "1" smd rect
			(at 0 0)
			(size 1.27 1.016)
			(layers "B.Cu" "B.Mask" "B.Paste")
			(net "PVCCIO_CPU0")
		)
		(pad "2" smd rect
			(at 0 1.778)
			(size 1.27 1.016)
			(layers "B.Cu" "B.Mask" "B.Paste")
			(net "GND")
		)
		(zone
			(layer "B.Cu")
			(hatch none 0.5)
			(connect_pads
				(clearance 0)
			)
			(min_thickness 0.25)
			(keepout
				(tracks not_allowed)
				(vias allowed)
				(pads allowed)
				(copperpour not_allowed)
				(footprints allowed)
			)
			(placement
				(enabled no)
				(sheetname "")
			)
			(fill
				(thermal_gap 0.5)
				(thermal_bridge_width 0.5)
				(island_removal_mode 0)
			)
			(polygon
				(pts
					(xy 278.068024 -72.222614) (xy 279.338024 -72.222614) (xy 279.338024 -72.984614) (xy 278.068024 -72.984614)
				)
			)
		)
	)
	(footprint ""
		(layer "B.Cu")
		(at 32.832802 -64.774064 90)
		(property "Reference" "C9P26"
			(at 0 0 90)
			(layer "B.SilkS")
			(hide yes)
			(effects
				(font
					(size 1.27 1.27)
				)
				(justify mirror)
			)
		)
		(property "Value" ""
			(at 0 0 90)
			(layer "B.Fab")
			(effects
				(font
					(size 1.27 1.27)
				)
				(justify mirror)
			)
		)
		(duplicate_pad_numbers_are_jumpers no)
		(fp_poly
			(pts
				(xy 0.7239 -0.2159) (xy -0.7239 -0.2159) (xy -0.7239 1.9939) (xy 0.7239 1.9939)
			)
			(stroke
				(width 0)
				(type default)
			)
			(fill no)
			(layer "B.CrtYd")
		)
		(fp_line
			(start 0.7239 -0.2159)
			(end 0.7239 1.9939)
			(stroke
				(width 0.1)
				(type default)
			)
			(layer "B.Fab")
		)
		(fp_line
			(start -0.7239 -0.2159)
			(end 0.7239 -0.2159)
			(stroke
				(width 0.1)
				(type default)
			)
			(layer "B.Fab")
		)
		(fp_line
			(start 0.7239 1.9939)
			(end -0.7239 1.9939)
			(stroke
				(width 0.1)
				(type default)
			)
			(layer "B.Fab")
		)
		(fp_line
			(start -0.7239 1.9939)
			(end -0.7239 -0.2159)
			(stroke
				(width 0.1)
				(type default)
			)
			(layer "B.Fab")
		)
		(pad "1" smd rect
			(at 0 0 270)
			(size 1.27 1.016)
			(layers "B.Cu" "B.Mask" "B.Paste")
			(net "VR_FET_SW_P12V_STBY_PVCCIN_CPU1")
		)
		(pad "2" smd rect
			(at 0 1.778 270)
			(size 1.27 1.016)
			(layers "B.Cu" "B.Mask" "B.Paste")
			(net "GND")
		)
		(zone
			(layer "B.Cu")
			(hatch none 0.5)
			(connect_pads
				(clearance 0)
			)
			(min_thickness 0.25)
			(keepout
				(tracks not_allowed)
				(vias allowed)
				(pads allowed)
				(copperpour not_allowed)
				(footprints allowed)
			)
			(placement
				(enabled no)
				(sheetname "")
			)
			(fill
				(thermal_gap 0.5)
				(thermal_bridge_width 0.5)
				(island_removal_mode 0)
			)
			(polygon
				(pts
					(xy 33.340802 -65.409064) (xy 33.340802 -64.139064) (xy 34.102802 -64.139064) (xy 34.102802 -65.409064)
				)
			)
		)
	)
)
